# Altium SchDoc records: Table_of_Contents.SchDoc
|HEADER=Protel for Windows - Schematic Capture Binary File Version 5.0|Weight=188|MinorVersion=4
|RECORD=31|FontIdCount=14|Size1=10|FontName1=Times New Roman|Size2=14|FontName2=Arial Narrow|Size3=12|FontName3=Arial|Size4=8|FontName4=Arial|Size5=10|FontName5=Arial|Size6=14|FontName6=Arial|Size7=9|FontName7=Arial|Size8=9|FontName8=Arial Narrow|Size9=22|FontName9=Arial Narrow|Size10=6|Rotation10=90|FontName10=Arial|Size11=6|FontName11=Arial|Size12=9|Rotation12=90|FontName12=Arial|Size13=24|FontName13=Arial|Size14=30|FontName14=Times New Roman|UseMBCS=T|IsBOC=T|HotSpotGridOn=T|HotSpotGridSize=4|SheetStyle=5|SystemFont=5|BorderOn=T|TitleBlockOn=T|SheetNumberSpaceSize=12|AreaColor=16317695|SnapGridOn=T|SnapGridSize=10|VisibleGridOn=T|VisibleGridSize=10|CustomX=1700|CustomY=1100|CustomXZones=8|CustomYZones=6|CustomMarginWidth=20|Display_Unit=0|ReferenceZoneStyle=1
|RECORD=39|IsNotAccesible=T|OwnerPartId=-1|FileName=C:\Users\<user>\Documents\Altium\AD22\Templates\ANSI B Landscape.SchDot
|RECORD=4|OwnerIndex=1|OwnerPartId=-1|Location.X=1345|Location.Y=1068|FontID=8|Text=REVISION
|RECORD=4|OwnerIndex=1|IndexInSheet=1|OwnerPartId=-1|Location.X=1460|Location.Y=1068|FontID=8|Text=DESCRIPTION
|RECORD=4|OwnerIndex=1|IndexInSheet=2|OwnerPartId=-1|Location.X=1592|Location.Y=1068|FontID=8|Text=DATE
|RECORD=4|OwnerIndex=1|IndexInSheet=3|OwnerPartId=-1|Location.X=1633|Location.Y=1068|FontID=8|Text=APPROVED
|RECORD=6|OwnerIndex=1|IndexInSheet=4|OwnerPartId=-1|LocationCount=3|X1=1340|Y1=1080|X2=1340|Y2=1065|X3=1680|Y3=1065
|RECORD=6|OwnerIndex=1|IndexInSheet=5|OwnerPartId=-1|LocationCount=2|X1=1380|Y1=1080|X2=1380|Y2=1065
|RECORD=6|OwnerIndex=1|IndexInSheet=6|OwnerPartId=-1|LocationCount=2|X1=1620|Y1=1080|X2=1620|Y2=1065
|RECORD=6|OwnerIndex=1|IndexInSheet=7|OwnerPartId=-1|LocationCount=2|X1=1580|Y1=1080|X2=1580|Y2=1065
|RECORD=6|OwnerIndex=1|IndexInSheet=8|OwnerPartId=-1|LocationCount=3|X1=1340|Y1=1070|X2=1340|Y2=1050|X3=1680|Y3=1050
|RECORD=6|OwnerIndex=1|IndexInSheet=9|OwnerPartId=-1|LocationCount=2|X1=1380|Y1=1065|X2=1380|Y2=1050
|RECORD=6|OwnerIndex=1|IndexInSheet=10|OwnerPartId=-1|LocationCount=2|X1=1580|Y1=1065|X2=1580|Y2=1050
|RECORD=6|OwnerIndex=1|IndexInSheet=11|OwnerPartId=-1|LocationCount=2|X1=1620|Y1=1065|X2=1620|Y2=1050
|RECORD=6|OwnerIndex=1|IndexInSheet=12|OwnerPartId=-1|LineWidth=1|LocationCount=2|X1=1695|Y1=184|X2=1700|Y2=184
|RECORD=4|OwnerIndex=1|IndexInSheet=13|OwnerPartId=-1|Location.X=1689|Location.Y=189|Orientation=3|FontID=10|Text=REV.
|RECORD=4|OwnerIndex=1|IndexInSheet=14|OwnerPartId=-1|Location.X=1689|Location.Y=174|Orientation=3|FontID=10|Text=SHT.
|RECORD=4|OwnerIndex=1|IndexInSheet=15|OwnerPartId=-1|Location.X=1695|Location.Y=259|Orientation=3|Justification=6|FontID=10|Text=DWG. NO.|IsMirrored=T
|RECORD=4|OwnerIndex=1|IndexInSheet=16|OwnerPartId=-1|Location.X=1680|Location.Y=258|Orientation=3|FontID=12|Text==DOC_NO_SCH_DWG
|RECORD=4|OwnerIndex=1|IndexInSheet=17|OwnerPartId=-1|Location.X=1680|Location.Y=182|Orientation=3|Justification=1|FontID=12|Text==ItemRevision
|RECORD=4|OwnerIndex=1|IndexInSheet=18|OwnerPartId=-1|Location.X=1680|Location.Y=169|Orientation=3|Justification=1|FontID=12|Text==SheetNumber
|RECORD=6|OwnerIndex=1|IndexInSheet=19|OwnerPartId=-1|LineWidth=1|LocationCount=3|X1=1695|Y1=160|X2=1695|Y2=260|X3=1680|Y3=260
|RECORD=6|OwnerIndex=1|IndexInSheet=20|OwnerPartId=-1|LocationCount=2|X1=1695|Y1=175|X2=1680|Y2=175
|RECORD=6|OwnerIndex=1|IndexInSheet=21|OwnerPartId=-1|LocationCount=2|X1=1695|Y1=190|X2=1680|Y2=190
|RECORD=6|OwnerIndex=1|IndexInSheet=22|OwnerPartId=-1|LineWidth=1|LocationCount=2|X1=1695|Y1=160|X2=1680|Y2=160
|RECORD=4|OwnerIndex=1|IndexInSheet=23|OwnerPartId=-1|Location.X=1312|Location.Y=1080|FontID=11|Text=REV.
|RECORD=4|OwnerIndex=1|IndexInSheet=24|OwnerPartId=-1|Location.X=1327|Location.Y=1080|FontID=11|Text=SHT.
|RECORD=4|OwnerIndex=1|IndexInSheet=25|OwnerPartId=-1|Location.X=1283|Location.Y=1086|Justification=6|FontID=11|Text=DWG. NO.|IsMirrored=T
|RECORD=4|OwnerIndex=1|IndexInSheet=26|OwnerPartId=-1|Location.X=1247|Location.Y=1085|FontID=7|Text==DOC_NO_SCH_DWG
|RECORD=4|OwnerIndex=1|IndexInSheet=27|OwnerPartId=-1|Location.X=1317|Location.Y=1085|Justification=1|FontID=7|Text==ItemRevision
|RECORD=4|OwnerIndex=1|IndexInSheet=28|OwnerPartId=-1|Location.X=1332|Location.Y=1085|Justification=1|FontID=7|Text==SheetNumber
|RECORD=6|OwnerIndex=1|IndexInSheet=29|OwnerPartId=-1|LineWidth=1|LocationCount=3|X1=1340|Y1=1095|X2=1240|Y2=1095|X3=1240|Y3=1080
|RECORD=6|OwnerIndex=1|IndexInSheet=30|OwnerPartId=-1|LocationCount=2|X1=1325|Y1=1095|X2=1325|Y2=1080
|RECORD=6|OwnerIndex=1|IndexInSheet=31|OwnerPartId=-1|LocationCount=2|X1=1310|Y1=1095|X2=1310|Y2=1080
|RECORD=6|OwnerIndex=1|IndexInSheet=32|OwnerPartId=-1|LineWidth=1|LocationCount=2|X1=1340|Y1=1095|X2=1340|Y2=1080
|RECORD=7|OwnerIndex=1|IndexInSheet=33|OwnerPartId=-1|IsSolid=T|LocationCount=3|X1=850|Y1=1080|X2=855|Y2=1090|X3=845|Y3=1090
|RECORD=7|OwnerIndex=1|IndexInSheet=34|OwnerPartId=-1|IsSolid=T|LocationCount=3|X1=850|Y1=20|X2=845|Y2=10|X3=855|Y3=10
|RECORD=7|OwnerIndex=1|IndexInSheet=35|OwnerPartId=-1|IsSolid=T|LocationCount=3|X1=1680|Y1=550|X2=1690|Y2=545|X3=1690|Y3=555
|RECORD=28|OwnerIndex=1|IndexInSheet=36|OwnerPartId=-1|UnionIndex=1|Location.X=25|Location.Y=1033|Corner.X=298|Corner.Y=1075|AreaColor=16777215|FontID=5|Alignment=1|WordWrap=T|Text=THIS DOCUMENT AND THE DATA DISCLOSED HEREIN OR HEREWITH IS THE PROPERTY OF ALTIUM LIMITED AND MAY BE FREELY DISTRIBUTED IN WHOLE. NO RIGHTS ARE RESERVED OR EXPRESS OR IMPLIED WARANTEE GIVEN.|TextMargin_Frac=5
|RECORD=6|OwnerIndex=1|IndexInSheet=37|OwnerPartId=-1|UnionIndex=1|LineWidth=1|LocationCount=5|X1=300|Y1=1080|X2=20|Y2=1080|X3=20|Y3=1032|X4=300|Y4=1032|X5=300|Y5=1080
|RECORD=13|OwnerIndex=1|IndexInSheet=38|OwnerPartId=-1|Location.Y=1100|Corner.X=1699|Corner.X_Frac=83312|Corner.Y=1100|LineWidth=1
|RECORD=13|OwnerIndex=1|IndexInSheet=39|OwnerPartId=-1|Location.X=1699|Location.X_Frac=83312|Location.Y=1100|Corner.X=1699|Corner.X_Frac=83312|Corner.Y_Frac=16696|LineWidth=1
|RECORD=13|OwnerIndex=1|IndexInSheet=40|OwnerPartId=-1|Location.X=1699|Location.X_Frac=83312|Location.Y_Frac=16696|Corner.Y_Frac=16696|LineWidth=1
|RECORD=13|OwnerIndex=1|IndexInSheet=41|OwnerPartId=-1|Location.Y_Frac=16696|Corner.Y=1100|LineWidth=1
|RECORD=13|OwnerIndex=1|IndexInSheet=42|OwnerPartId=-1|Location.X=20|Location.X_Frac=12|Location.Y=1079|Location.Y_Frac=99791|Corner.X=1679|Corner.X_Frac=83296|Corner.Y=1079|Corner.Y_Frac=99791|LineWidth=1
|RECORD=13|OwnerIndex=1|IndexInSheet=43|OwnerPartId=-1|Location.X=1679|Location.X_Frac=83296|Location.Y=1079|Location.Y_Frac=99791|Corner.X=1679|Corner.X_Frac=83296|Corner.Y=20|Corner.Y_Frac=16904|LineWidth=1
|RECORD=13|OwnerIndex=1|IndexInSheet=44|OwnerPartId=-1|Location.X=1679|Location.X_Frac=83296|Location.Y=20|Location.Y_Frac=16904|Corner.X=20|Corner.X_Frac=12|Corner.Y=20|Corner.Y_Frac=16904|LineWidth=1
|RECORD=13|OwnerIndex=1|IndexInSheet=45|OwnerPartId=-1|Location.X=20|Location.X_Frac=12|Location.Y=20|Location.Y_Frac=16904|Corner.X=20|Corner.X_Frac=12|Corner.Y=1079|Corner.Y_Frac=99791|LineWidth=1
|RECORD=13|OwnerIndex=1|IndexInSheet=46|OwnerPartId=-1|Location.X=1487|Location.X_Frac=50000|Location.Y=20|Corner.X=1487|Corner.X_Frac=50000|LineWidth=1
|RECORD=13|OwnerIndex=1|IndexInSheet=47|OwnerPartId=-1|Location.X=1487|Location.X_Frac=50000|Location.Y=1080|Corner.X=1487|Corner.X_Frac=50000|Corner.Y=1100|LineWidth=1
|RECORD=13|OwnerIndex=1|IndexInSheet=48|OwnerPartId=-1|Location.X=1275|Location.Y=20|Corner.X=1275|LineWidth=1
|RECORD=13|OwnerIndex=1|IndexInSheet=49|OwnerPartId=-1|Location.X=1275|Location.Y=1095|Corner.X=1275|Corner.Y=1100|LineWidth=1
|RECORD=13|OwnerIndex=1|IndexInSheet=50|OwnerPartId=-1|Location.X=1062|Location.X_Frac=50000|Location.Y=20|Corner.X=1062|Corner.X_Frac=50000|LineWidth=1
|RECORD=13|OwnerIndex=1|IndexInSheet=51|OwnerPartId=-1|Location.X=1062|Location.X_Frac=50000|Location.Y=1080|Corner.X=1062|Corner.X_Frac=50000|Corner.Y=1100|LineWidth=1
|RECORD=13|OwnerIndex=1|IndexInSheet=52|OwnerPartId=-1|Location.X=850|Location.Y=20|Corner.X=850|LineWidth=1
|RECORD=13|OwnerIndex=1|IndexInSheet=53|OwnerPartId=-1|Location.X=850|Location.Y=1080|Corner.X=850|Corner.Y=1100|LineWidth=1
|RECORD=13|OwnerIndex=1|IndexInSheet=54|OwnerPartId=-1|Location.X=637|Location.X_Frac=50000|Location.Y=20|Corner.X=637|Corner.X_Frac=50000|LineWidth=1
|RECORD=13|OwnerIndex=1|IndexInSheet=55|OwnerPartId=-1|Location.X=637|Location.X_Frac=50000|Location.Y=1080|Corner.X=637|Corner.X_Frac=50000|Corner.Y=1100|LineWidth=1
|RECORD=13|OwnerIndex=1|IndexInSheet=56|OwnerPartId=-1|Location.X=425|Location.Y=20|Corner.X=425|LineWidth=1
|RECORD=13|OwnerIndex=1|IndexInSheet=57|OwnerPartId=-1|Location.X=425|Location.Y=1080|Corner.X=425|Corner.Y=1100|LineWidth=1
|RECORD=13|OwnerIndex=1|IndexInSheet=58|OwnerPartId=-1|Location.X=212|Location.X_Frac=50000|Location.Y=20|Corner.X=212|Corner.X_Frac=50000|LineWidth=1
|RECORD=13|OwnerIndex=1|IndexInSheet=59|OwnerPartId=-1|Location.X=212|Location.X_Frac=50000|Location.Y=1080|Corner.X=212|Corner.X_Frac=50000|Corner.Y=1100|LineWidth=1
|RECORD=13|OwnerIndex=1|IndexInSheet=60|OwnerPartId=-1|Location.X=20|Location.Y=916|Location.Y_Frac=66664|Corner.Y=916|Corner.Y_Frac=66664|LineWidth=1
|RECORD=13|OwnerIndex=1|IndexInSheet=61|OwnerPartId=-1|Location.X=1680|Location.Y=916|Location.Y_Frac=66664|Corner.X=1700|Corner.Y=916|Corner.Y_Frac=66664|LineWidth=1
|RECORD=13|OwnerIndex=1|IndexInSheet=62|OwnerPartId=-1|Location.X=20|Location.Y=733|Location.Y_Frac=33328|Corner.Y=733|Corner.Y_Frac=33328|LineWidth=1
|RECORD=13|OwnerIndex=1|IndexInSheet=63|OwnerPartId=-1|Location.X=1680|Location.Y=733|Location.Y_Frac=33328|Corner.X=1700|Corner.Y=733|Corner.Y_Frac=33328|LineWidth=1
|RECORD=13|OwnerIndex=1|IndexInSheet=64|OwnerPartId=-1|Location.X=20|Location.Y=550|Corner.Y=550|LineWidth=1
|RECORD=13|OwnerIndex=1|IndexInSheet=65|OwnerPartId=-1|Location.X=1680|Location.Y=550|Corner.X=1700|Corner.Y=550|LineWidth=1
|RECORD=13|OwnerIndex=1|IndexInSheet=66|OwnerPartId=-1|Location.X=20|Location.Y=366|Location.Y_Frac=66664|Corner.Y=366|Corner.Y_Frac=66664|LineWidth=1
|RECORD=13|OwnerIndex=1|IndexInSheet=67|OwnerPartId=-1|Location.X=1680|Location.Y=366|Location.Y_Frac=66664|Corner.X=1700|Corner.Y=366|Corner.Y_Frac=66664|LineWidth=1
|RECORD=13|OwnerIndex=1|IndexInSheet=68|OwnerPartId=-1|Location.X=20|Location.Y=183|Location.Y_Frac=33330|Corner.Y=183|Corner.Y_Frac=33330|LineWidth=1
|RECORD=7|OwnerIndex=1|IndexInSheet=69|OwnerPartId=-1|IsSolid=T|LocationCount=3|X1=20|Y1=550|X2=10|Y2=545|X3=10|Y3=555
|RECORD=4|OwnerIndex=1|IndexInSheet=70|OwnerPartId=-1|Location.X=1348|Location.Y=71|FontID=13|Text==title
|RECORD=4|OwnerIndex=1|IndexInSheet=71|OwnerPartId=-1|Location.X=1450|Location.Y=40|FontID=2|Text==DOC_NO_SCH_DWG
|RECORD=6|OwnerIndex=1|IndexInSheet=72|OwnerPartId=-1|LocationCount=2|X1=1405|Y1=65|X2=1405|Y2=35
|RECORD=6|OwnerIndex=1|IndexInSheet=73|OwnerPartId=-1|LocationCount=2|X1=1680|Y1=35|X2=1320|Y2=35
|RECORD=6|OwnerIndex=1|IndexInSheet=74|OwnerPartId=-1|LocationCount=2|X1=1650|Y1=65|X2=1650|Y2=35
|RECORD=4|OwnerIndex=1|IndexInSheet=75|OwnerPartId=-1|Location.X=1330|Location.Y=35|FontID=9|Text=B
|RECORD=4|OwnerIndex=1|IndexInSheet=76|OwnerPartId=-1|Location.X=1428|Location.Y=20|FontID=3|Text==DocumentName
|RECORD=4|OwnerIndex=1|IndexInSheet=77|OwnerPartId=-1|Location.X=1615|Location.Y=20|FontID=3|Text==SheetNumber
|RECORD=4|OwnerIndex=1|IndexInSheet=78|OwnerPartId=-1|Location.X=1655|Location.Y=20|FontID=3|Text==SheetTotal
|RECORD=4|OwnerIndex=1|IndexInSheet=79|OwnerPartId=-1|Location.X=1323|Location.Y=100|Justification=3|FontID=4|Text=TITLE
|RECORD=4|OwnerIndex=1|IndexInSheet=80|OwnerPartId=-1|Location.X=1328|Location.Y=60|Justification=3|FontID=4|Text=SIZE
|RECORD=4|OwnerIndex=1|IndexInSheet=81|OwnerPartId=-1|Location.X=1407|Location.Y=60|Justification=3|FontID=4|Text=DWG NO.
|RECORD=4|OwnerIndex=1|IndexInSheet=82|OwnerPartId=-1|Location.X=1387|Location.Y=30|Justification=3|FontID=4|Text=FILE NAME
|RECORD=4|OwnerIndex=1|IndexInSheet=83|OwnerPartId=-1|Location.X=1582|Location.Y=30|Justification=3|FontID=4|Text=SHEET
|RECORD=4|OwnerIndex=1|IndexInSheet=84|OwnerPartId=-1|Location.X=1640|Location.Y=30|Justification=3|FontID=4|Text=OF
|RECORD=4|OwnerIndex=1|IndexInSheet=85|OwnerPartId=-1|Location.X=1657|Location.Y=60|Justification=3|FontID=4|Text=REV
|RECORD=6|OwnerIndex=1|IndexInSheet=86|OwnerPartId=-1|LocationCount=2|X1=1385|Y1=35|X2=1385|Y2=20
|RECORD=4|OwnerIndex=1|IndexInSheet=87|OwnerPartId=-1|Location.X=1322|Location.Y=30|Justification=3|FontID=4|Text=SCALE:
|RECORD=4|OwnerIndex=1|IndexInSheet=88|OwnerPartId=-1|Location.X=1349|Location.Y=20|FontID=3|Text==SCH_SCALE
|RECORD=6|OwnerIndex=1|IndexInSheet=89|OwnerPartId=-1|LocationCount=2|X1=1580|Y1=35|X2=1580|Y2=20
|RECORD=4|OwnerIndex=1|IndexInSheet=90|OwnerPartId=-1|Location.X=1355|Location.Y=40|FontID=6|Text==CAGE_CODE
|RECORD=4|OwnerIndex=1|IndexInSheet=91|OwnerPartId=-1|Location.X=1352|Location.Y=56|FontID=4|Text=CAGE CODE
|RECORD=6|OwnerIndex=1|IndexInSheet=92|OwnerPartId=-1|LocationCount=2|X1=1350|Y1=65|X2=1350|Y2=35
|RECORD=6|OwnerIndex=1|IndexInSheet=93|OwnerPartId=-1|LineWidth=1|LocationCount=2|X1=1680|Y1=120|X2=1320|Y2=120
|RECORD=6|OwnerIndex=1|IndexInSheet=94|OwnerPartId=-1|LineWidth=1|LocationCount=2|X1=1680|Y1=160|X2=1320|Y2=160
|RECORD=4|OwnerIndex=1|IndexInSheet=95|OwnerPartId=-1|Location.X=1323|Location.Y=150|FontID=4|Text=PROJECT
|RECORD=6|OwnerIndex=1|IndexInSheet=96|OwnerPartId=-1|LocationCount=2|X1=1390|Y1=160|X2=1390|Y2=120
|RECORD=4|OwnerIndex=1|IndexInSheet=97|OwnerPartId=-1|Location.X=1325|Location.Y=130|FontID=6|Text==Project
|RECORD=4|OwnerIndex=1|IndexInSheet=98|OwnerPartId=-1|Location.X=1613|Location.Y=129|Justification=2|FontID=7|Text==Address3|IsMirrored=T
|RECORD=4|OwnerIndex=1|IndexInSheet=99|OwnerPartId=-1|Location.X=1614|Location.Y=120|Justification=2|FontID=7|Text==Address4|IsMirrored=T
|RECORD=4|OwnerIndex=1|IndexInSheet=100|OwnerPartId=-1|Location.X=1614|Location.Y=150|Justification=2|FontID=7|Text==Address1|IsMirrored=T
|RECORD=4|OwnerIndex=1|IndexInSheet=101|OwnerPartId=-1|Location.X=1614|Location.Y=144|Justification=5|FontID=7|Text==Address2|IsMirrored=T
|RECORD=6|OwnerIndex=1|IndexInSheet=102|OwnerPartId=1|LineWidth=1|LocationCount=2|X1=1320|Y1=65|X2=1320|Y2=35
|RECORD=6|OwnerIndex=1|IndexInSheet=103|OwnerPartId=1|LineWidth=1|LocationCount=2|X1=1320|Y1=35|X2=1320|Y2=20
|RECORD=6|OwnerIndex=1|IndexInSheet=104|OwnerPartId=1|LineWidth=1|LocationCount=2|X1=1320|Y1=65|X2=1320|Y2=120
|RECORD=6|OwnerIndex=1|IndexInSheet=105|OwnerPartId=1|LineWidth=1|LocationCount=2|X1=1320|Y1=120|X2=1320|Y2=160
|RECORD=6|OwnerIndex=1|IndexInSheet=106|OwnerPartId=1|LineWidth=1|LocationCount=3|X1=1320|Y1=160|X2=1180|Y2=160|X3=1180|Y3=20
|RECORD=4|OwnerIndex=1|IndexInSheet=107|OwnerPartId=1|Location.X=1212|Location.Y=145|FontID=4|Text=APPROVALS
|RECORD=4|OwnerIndex=1|IndexInSheet=108|OwnerPartId=1|Location.X=1290|Location.Y=145|FontID=4|Text=DATE
|RECORD=4|OwnerIndex=1|IndexInSheet=109|OwnerPartId=1|Location.X=1182|Location.Y=131|FontID=4|Text=ENG:
|RECORD=4|OwnerIndex=1|IndexInSheet=110|OwnerPartId=1|Location.X=1182|Location.Y=116|FontID=4|Text=DSN:
|RECORD=6|OwnerIndex=1|IndexInSheet=111|OwnerPartId=1|LocationCount=2|X1=1180|Y1=125|X2=1320|Y2=125
|RECORD=6|OwnerIndex=1|IndexInSheet=112|OwnerPartId=1|LocationCount=2|X1=1180|Y1=140|X2=1320|Y2=140
|RECORD=6|OwnerIndex=1|IndexInSheet=113|OwnerPartId=1|LocationCount=2|X1=1280|Y1=160|X2=1280|Y2=95
|RECORD=4|OwnerIndex=1|IndexInSheet=114|OwnerPartId=1|Location.X=1210|Location.Y=125|FontID=4|Text==Engineer
|RECORD=4|OwnerIndex=1|IndexInSheet=115|OwnerPartId=1|Location.X=1210|Location.Y=110|FontID=4|Text==DrawnBy
|RECORD=4|OwnerIndex=1|IndexInSheet=116|OwnerPartId=1|Location.X=1285|Location.Y=125|FontID=4|Text==ENG_APP_DATE
|RECORD=4|OwnerIndex=1|IndexInSheet=117|OwnerPartId=1|Location.X=1285|Location.Y=110|FontID=4|Text==DSN_APP_DATE
|RECORD=6|OwnerIndex=1|IndexInSheet=118|OwnerPartId=1|LineWidth=1|LocationCount=2|X1=1180|Y1=95|X2=1320|Y2=95
|RECORD=6|OwnerIndex=1|IndexInSheet=119|OwnerPartId=1|LocationCount=2|X1=1180|Y1=110|X2=1320|Y2=110
|RECORD=4|OwnerIndex=1|IndexInSheet=120|OwnerPartId=1|Location.X=1182|Location.Y=101|FontID=4|Text=CHK:
|RECORD=4|OwnerIndex=1|IndexInSheet=121|OwnerPartId=1|Location.X=1285|Location.Y=95|FontID=4|Text==CHK_APP_DATE
|RECORD=6|OwnerIndex=1|IndexInSheet=122|OwnerPartId=1|LocationCount=2|X1=1180|Y1=65|X2=1320|Y2=65
|RECORD=6|OwnerIndex=1|IndexInSheet=123|OwnerPartId=1|LocationCount=2|X1=1180|Y1=80|X2=1320|Y2=80
|RECORD=6|OwnerIndex=1|IndexInSheet=124|OwnerPartId=1|LocationCount=2|X1=1180|Y1=35|X2=1320|Y2=35
|RECORD=6|OwnerIndex=1|IndexInSheet=125|OwnerPartId=1|LocationCount=2|X1=1180|Y1=50|X2=1320|Y2=50
|RECORD=4|OwnerIndex=1|IndexInSheet=126|OwnerPartId=-1|Location.X=1204|Location.Y=82|FontID=4|Text=REFERENCE DOCUMENTS
|RECORD=4|OwnerIndex=1|IndexInSheet=127|OwnerPartId=1|Location.X=1182|Location.Y=71|FontID=4|Text=BOM:
|RECORD=4|OwnerIndex=1|IndexInSheet=128|OwnerPartId=1|Location.X=1183|Location.Y=56|FontID=4|Text=ASSY DWG:
|RECORD=4|OwnerIndex=1|IndexInSheet=129|OwnerPartId=1|Location.X=1182|Location.Y=41|FontID=4|Text=FAB DWG:
|RECORD=4|OwnerIndex=1|IndexInSheet=130|OwnerPartId=1|Location.X=1182|Location.Y=26|FontID=4|Text=PCB DWG:
|RECORD=4|OwnerIndex=1|IndexInSheet=131|OwnerPartId=-1|Location.X=1228|Location.Y=22|FontID=5|Text==PCB_DWG_NO
|RECORD=4|OwnerIndex=1|IndexInSheet=132|OwnerPartId=-1|Location.X=1228|Location.Y=37|FontID=5|Text==DOC_NO_FAB_DWG
|RECORD=4|OwnerIndex=1|IndexInSheet=133|OwnerPartId=-1|Location.X=1228|Location.Y=52|FontID=5|Text==DOC_NO_ASSY_DWG
|RECORD=4|OwnerIndex=1|IndexInSheet=134|OwnerPartId=-1|Location.X=1228|Location.Y=68|FontID=5|Text==DOC_NO_BOM
|RECORD=4|OwnerIndex=1|IndexInSheet=135|OwnerPartId=1|Location.X=1210|Location.Y=96|FontID=4|Text==CheckedBy
|RECORD=4|OwnerIndex=1|IndexInSheet=136|OwnerPartId=-1|Location.X=1591|Location.Y=104|FontID=3|Text==Item
|RECORD=6|OwnerIndex=1|IndexInSheet=137|OwnerPartId=-1|LineWidth=1|LocationCount=2|X1=1320|Y1=105|X2=1680|Y2=105
|RECORD=4|OwnerIndex=1|IndexInSheet=138|OwnerPartId=-1|Location.X=1322|Location.Y=115|Justification=3|FontID=4|Text=PROJECT REVISION:
|RECORD=4|OwnerIndex=1|IndexInSheet=139|OwnerPartId=-1|Location.X=1542|Location.Y=116|Justification=3|FontID=4|Text=DESIGN ITEM:
|RECORD=4|OwnerIndex=1|IndexInSheet=140|OwnerPartId=-1|Location.X=1432|Location.Y=116|Justification=3|FontID=4|Text=DOCUMENT REVISION:
|RECORD=6|OwnerIndex=1|IndexInSheet=141|OwnerPartId=-1|LocationCount=2|X1=1430|Y1=120|X2=1430|Y2=105
|RECORD=6|OwnerIndex=1|IndexInSheet=142|OwnerPartId=-1|LocationCount=2|X1=1541|Y1=120|X2=1541|Y2=105
|RECORD=4|OwnerIndex=1|IndexInSheet=143|OwnerPartId=-1|Location.X=1392|Location.Y=104|FontID=3|Text==VersionControl_ProjFolderRevNumber
|RECORD=4|OwnerIndex=1|IndexInSheet=144|OwnerPartId=-1|Location.X=1511|Location.Y=104|FontID=3|Text==VersionControl_RevNumber
|RECORD=6|OwnerIndex=1|IndexInSheet=145|OwnerPartId=-1|LineWidth=1|LocationCount=2|X1=1320|Y1=65|X2=1680|Y2=65
|RECORD=4|OwnerIndex=1|IndexInSheet=146|OwnerPartId=-1|Location.X=1662|Location.Y=41|FontID=3|Text==ItemRevision
|RECORD=30|OwnerIndex=1|IndexInSheet=147|OwnerPartId=-1|Location.X=1398|Location.Y=123|Corner.X=1558|Corner.X_Frac=41666|Corner.Y=158|KeepAspect=T|EmbedImage=T|FileName=Z:\Altium Project Template\Altium Logo\Altm black.jpg
|RECORD=41|IndexInSheet=1|OwnerPartId=-1|Location.X=19|Location.Y=9|Color=8388608|FontID=1|IsHidden=T|Text=sch_PageDescription|Name=sch_PageDescription
|RECORD=41|IndexInSheet=2|OwnerPartId=-1|Location.X=179|Location.Y=5|Color=8388608|FontID=1|IsHidden=T|Text=sch_PageTitle|Name=sch_PageTitle
|RECORD=41|IndexInSheet=3|OwnerPartId=-1|Location.X=179|Location.Y=5|Color=8388608|FontID=1|IsHidden=T|Text=*|Name=PageDate
|RECORD=41|IndexInSheet=4|OwnerPartId=-1|Color=8388608|FontID=1|IsHidden=T|Text=*|Name=CurrentTime
|RECORD=41|IndexInSheet=5|OwnerPartId=-1|Color=8388608|FontID=1|IsHidden=T|Text=*|Name=CurrentDate
|RECORD=41|IndexInSheet=6|OwnerPartId=-1|Color=8388608|FontID=1|IsHidden=T|Text=*|Name=Time
|RECORD=41|IndexInSheet=7|OwnerPartId=-1|Color=8388608|FontID=1|IsHidden=T|Text=*|Name=Date
|RECORD=41|IndexInSheet=8|OwnerPartId=-1|Color=8388608|FontID=1|IsHidden=T|Text=*|Name=DocumentFullPathAndName
|RECORD=41|IndexInSheet=9|OwnerPartId=-1|Color=8388608|FontID=1|IsHidden=T|Text=*|Name=DocumentName
|RECORD=41|IndexInSheet=10|OwnerPartId=-1|Color=8388608|FontID=1|IsHidden=T|Text=*|Name=ModifiedDate
|RECORD=41|IndexInSheet=11|OwnerPartId=-1|Color=8388608|FontID=1|IsHidden=T|Text=*|Name=ApprovedBy
|RECORD=41|IndexInSheet=12|OwnerPartId=-1|Color=8388608|FontID=1|IsHidden=T|Text=*|Name=CheckedBy
|RECORD=41|IndexInSheet=13|OwnerPartId=-1|Color=8388608|FontID=1|IsHidden=T|Text=*|Name=Author
|RECORD=41|IndexInSheet=14|OwnerPartId=-1|Color=8388608|FontID=1|IsHidden=T|Text=*|Name=CompanyName
|RECORD=41|IndexInSheet=15|OwnerPartId=-1|Color=8388608|FontID=1|IsHidden=T|Text=*|Name=DrawnBy
|RECORD=41|IndexInSheet=16|OwnerPartId=-1|Color=8388608|FontID=1|IsHidden=T|Text=*|Name=Engineer
|RECORD=41|IndexInSheet=17|OwnerPartId=-1|Color=8388608|FontID=1|IsHidden=T|Text=ORGANIZATION|Name=Organization
|RECORD=41|IndexInSheet=18|OwnerPartId=-1|Color=8388608|FontID=1|IsHidden=T|Text=ADDRESS 1|Name=Address1
|RECORD=41|IndexInSheet=19|OwnerPartId=-1|Color=8388608|FontID=1|IsHidden=T|Text=ADDRESS 2|Name=Address2
|RECORD=41|IndexInSheet=20|OwnerPartId=-1|Color=8388608|FontID=1|IsHidden=T|Text=ADDRESS 3|Name=Address3
|RECORD=41|IndexInSheet=21|OwnerPartId=-1|Color=8388608|FontID=1|IsHidden=T|Text=ADDRESS 4|Name=Address4
|RECORD=41|IndexInSheet=22|OwnerPartId=-1|Color=8388608|FontID=1|IsHidden=T|Text=*|Name=Title
|RECORD=41|IndexInSheet=23|OwnerPartId=-1|Color=8388608|FontID=1|IsHidden=T|Text=*|Name=DocumentNumber
|RECORD=41|IndexInSheet=24|OwnerPartId=-1|Color=8388608|FontID=1|IsHidden=T|Text=-|Name=Revision
|RECORD=41|IndexInSheet=25|OwnerPartId=-1|Color=8388608|FontID=1|IsHidden=T|Text=1|Name=SheetNumber
|RECORD=41|IndexInSheet=26|OwnerPartId=-1|Color=8388608|FontID=1|IsHidden=T|Text=3|Name=SheetTotal
|RECORD=41|IndexInSheet=27|OwnerPartId=-1|Color=8388608|FontID=1|IsHidden=T|Text=*|Name=ImagePath|ReadOnlyState=1
|RECORD=41|IndexInSheet=28|OwnerPartId=-1|Color=8388608|FontID=1|IsHidden=T|Text=*|Name=Rule|ReadOnlyState=1
|RECORD=41|IndexInSheet=29|OwnerPartId=-1|Color=8388608|FontID=1|IsHidden=T|Text=*|Name=ProjectName|ReadOnlyState=1
|RECORD=41|IndexInSheet=30|OwnerPartId=-1|Location.X=839|Location.Y=9|Color=8388608|FontID=1|IsHidden=T|Text=*|Name=Title2
|RECORD=41|IndexInSheet=31|OwnerPartId=-1|Location.Y=-10|Color=8388608|FontID=1|IsHidden=T|Text=*|Name=Project
|RECORD=41|IndexInSheet=32|OwnerPartId=-1|Location.Y=-10|Color=8388608|FontID=1|IsHidden=T|Text=--/--/--|Name=ENG_APP_DATE
|RECORD=41|IndexInSheet=33|OwnerPartId=-1|Location.Y=-10|Color=8388608|FontID=1|IsHidden=T|Text=--/--/--|Name=DSN_APP_DATE
|RECORD=41|IndexInSheet=34|OwnerPartId=-1|Location.Y=-10|Color=8388608|FontID=1|IsHidden=T|Text=--/--/--|Name=CHK_APP_DATE
|RECORD=41|IndexInSheet=35|OwnerPartId=-1|Color=8388608|FontID=1|IsHidden=T|Text=*|Name=Application_BuildNumber|ReadOnlyState=1
|RECORD=4|IndexInSheet=36|OwnerPartId=-1|Location.X=40|Location.Y=680|Color=8388608|FontID=14|Text=01. Table of Contents
|RECORD=4|IndexInSheet=37|OwnerPartId=-1|Location.X=40|Location.Y=650|Color=8388608|FontID=14|Text=02. ZED-F9T
|RECORD=4|IndexInSheet=38|OwnerPartId=-1|Location.X=40|Location.Y=620|Color=8388608|FontID=14|Text=03. Antenna Supervisor Circuit